(kicad_pcb
	(version 20260206)
	(generator "pcbnew")
	(generator_version "10.0")
	(general
		(thickness 1.6)
		(legacy_teardrops no)
	)
	(paper "A4")
	(title_block
		(title "04192023_DAF0TMB3IC0_F0TG_MB_C_brd_V02_OCP.brd")
		(comment 1 "Grand Teton / footprints 840-845 of 8354")
	)
	(layers
		(0 "F.Cu" signal "TOP")
		(4 "In1.Cu" signal "GND")
		(6 "In2.Cu" signal "IN1")
		(8 "In3.Cu" signal "GND1")
		(10 "In4.Cu" signal "IN2")
		(12 "In5.Cu" signal "GND2")
		(14 "In6.Cu" signal "IN3")
		(16 "In7.Cu" signal "GND3")
		(18 "In8.Cu" signal "VCC")
		(20 "In9.Cu" signal "VCC1")
		(22 "In10.Cu" signal "GND4")
		(24 "In11.Cu" signal "IN4")
		(26 "In12.Cu" signal "GND5")
		(28 "In13.Cu" signal "IN5")
		(30 "In14.Cu" signal "GND6")
		(32 "In15.Cu" signal "IN6")
		(34 "In16.Cu" signal "GND7")
		(2 "B.Cu" signal "BOTTOM")
		(9 "F.Adhes" user "F.Adhesive")
		(11 "B.Adhes" user "B.Adhesive")
		(13 "F.Paste" user "Package Geometry/Pastemask Top")
		(15 "B.Paste" user "Package Geometry/Pastemask Bottom")
		(5 "F.SilkS" user "Ref Des/Silkscreen Top")
		(7 "B.SilkS" user "Ref Des/Silkscreen Bottom")
		(1 "F.Mask" user "Board Geometry/Soldermask Top")
		(3 "B.Mask" user "Board Geometry/Soldermask Bottom")
		(17 "Dwgs.User" user "User.Drawings")
		(19 "Cmts.User" user "User.Comments")
		(21 "Eco1.User" user "User.Eco1")
		(23 "Eco2.User" user "User.Eco2")
		(25 "Edge.Cuts" user "Board Geometry/Outline")
		(27 "Margin" user)
		(31 "F.CrtYd" user "Package Geometry/Place Bound Top")
		(29 "B.CrtYd" user "Package Geometry/Place Bound Bottom")
		(35 "F.Fab" user "Ref Des/Assembly Top")
		(33 "B.Fab" user "Ref Des/Assembly Bottom")
	)
	(footprint ""
		(layer "F.Cu")
		(at 21.876258 -427.580298 90)
		(property "Reference" "R6166"
			(at 0 0 90)
			(layer "F.SilkS")
			(hide yes)
			(effects
				(font
					(size 1.27 1.27)
				)
			)
		)
		(property "Value" ""
			(at 0 0 90)
			(layer "F.Fab")
			(effects
				(font
					(size 1.27 1.27)
				)
			)
		)
		(duplicate_pad_numbers_are_jumpers no)
		(fp_line
			(start 0.7874 -0.4064)
			(end 0.7874 0.4064)
			(stroke
				(width 0.1524)
				(type default)
			)
			(layer "F.SilkS")
		)
		(fp_line
			(start -0.7874 -0.4064)
			(end 0.7874 -0.4064)
			(stroke
				(width 0.1524)
				(type default)
			)
			(layer "F.SilkS")
		)
		(fp_line
			(start 0.7874 0.4064)
			(end -0.7874 0.4064)
			(stroke
				(width 0.1524)
				(type default)
			)
			(layer "F.SilkS")
		)
		(fp_line
			(start -0.7874 0.4064)
			(end -0.7874 -0.4064)
			(stroke
				(width 0.1524)
				(type default)
			)
			(layer "F.SilkS")
		)
		(fp_line
			(start -0.12065 -0.305054)
			(end -0.12065 -0.2794)
			(stroke
				(width 0.1)
				(type default)
			)
			(layer "F.Fab")
		)
		(fp_line
			(start -0.67945 -0.305054)
			(end -0.12065 -0.305054)
			(stroke
				(width 0.1)
				(type default)
			)
			(layer "F.Fab")
		)
		(fp_line
			(start 0.67945 -0.3048)
			(end 0.67945 0.3048)
			(stroke
				(width 0.1)
				(type default)
			)
			(layer "F.Fab")
		)
		(fp_line
			(start 0.12065 -0.3048)
			(end 0.67945 -0.3048)
			(stroke
				(width 0.1)
				(type default)
			)
			(layer "F.Fab")
		)
		(fp_line
			(start 0.12065 -0.2794)
			(end 0.12065 -0.3048)
			(stroke
				(width 0.1)
				(type default)
			)
			(layer "F.Fab")
		)
		(fp_line
			(start -0.12065 -0.2794)
			(end 0.12065 -0.2794)
			(stroke
				(width 0.1)
				(type default)
			)
			(layer "F.Fab")
		)
		(fp_line
			(start 0.120396 0.2794)
			(end -0.12065 0.2794)
			(stroke
				(width 0.1)
				(type default)
			)
			(layer "F.Fab")
		)
		(fp_line
			(start -0.12065 0.2794)
			(end -0.12065 0.3048)
			(stroke
				(width 0.1)
				(type default)
			)
			(layer "F.Fab")
		)
		(fp_line
			(start 0.67945 0.3048)
			(end 0.120396 0.3048)
			(stroke
				(width 0.1)
				(type default)
			)
			(layer "F.Fab")
		)
		(fp_line
			(start 0.120396 0.3048)
			(end 0.120396 0.2794)
			(stroke
				(width 0.1)
				(type default)
			)
			(layer "F.Fab")
		)
		(fp_line
			(start -0.12065 0.3048)
			(end -0.67945 0.3048)
			(stroke
				(width 0.1)
				(type default)
			)
			(layer "F.Fab")
		)
		(fp_line
			(start -0.67945 0.3048)
			(end -0.67945 -0.305054)
			(stroke
				(width 0.1)
				(type default)
			)
			(layer "F.Fab")
		)
		(pad "1" smd circle
			(at -0.40005 0 90)
			(size 0 0)
			(layers "F.Cu" "F.Mask" "F.Paste")
			(net "FM_P2E_BUF2_EQB0")
		)
		(pad "2" smd circle
			(at 0.40005 0 90)
			(size 0 0)
			(layers "F.Cu" "F.Mask" "F.Paste")
			(net "GND")
		)
	)
	(footprint ""
		(layer "F.Cu")
		(at 315.214 -366.395 90)
		(property "Reference" "PC15"
			(at 0 0 90)
			(layer "F.SilkS")
			(hide yes)
			(effects
				(font
					(size 1.27 1.27)
				)
			)
		)
		(property "Value" ""
			(at 0 0 90)
			(layer "F.Fab")
			(effects
				(font
					(size 1.27 1.27)
				)
			)
		)
		(duplicate_pad_numbers_are_jumpers no)
		(fp_line
			(start 0.7874 -0.4064)
			(end 0.7874 0.4064)
			(stroke
				(width 0.1524)
				(type default)
			)
			(layer "F.SilkS")
		)
		(fp_line
			(start -0.7874 -0.4064)
			(end 0.7874 -0.4064)
			(stroke
				(width 0.1524)
				(type default)
			)
			(layer "F.SilkS")
		)
		(fp_line
			(start 0.7874 0.4064)
			(end -0.7874 0.4064)
			(stroke
				(width 0.1524)
				(type default)
			)
			(layer "F.SilkS")
		)
		(fp_line
			(start -0.7874 0.4064)
			(end -0.7874 -0.4064)
			(stroke
				(width 0.1524)
				(type default)
			)
			(layer "F.SilkS")
		)
		(fp_line
			(start -0.12065 -0.305054)
			(end -0.12065 -0.2794)
			(stroke
				(width 0.1)
				(type default)
			)
			(layer "F.Fab")
		)
		(fp_line
			(start -0.67945 -0.305054)
			(end -0.12065 -0.305054)
			(stroke
				(width 0.1)
				(type default)
			)
			(layer "F.Fab")
		)
		(fp_line
			(start 0.67945 -0.3048)
			(end 0.67945 0.3048)
			(stroke
				(width 0.1)
				(type default)
			)
			(layer "F.Fab")
		)
		(fp_line
			(start 0.12065 -0.3048)
			(end 0.67945 -0.3048)
			(stroke
				(width 0.1)
				(type default)
			)
			(layer "F.Fab")
		)
		(fp_line
			(start 0.12065 -0.2794)
			(end 0.12065 -0.3048)
			(stroke
				(width 0.1)
				(type default)
			)
			(layer "F.Fab")
		)
		(fp_line
			(start -0.12065 -0.2794)
			(end 0.12065 -0.2794)
			(stroke
				(width 0.1)
				(type default)
			)
			(layer "F.Fab")
		)
		(fp_line
			(start 0.120396 0.2794)
			(end -0.12065 0.2794)
			(stroke
				(width 0.1)
				(type default)
			)
			(layer "F.Fab")
		)
		(fp_line
			(start -0.12065 0.2794)
			(end -0.12065 0.3048)
			(stroke
				(width 0.1)
				(type default)
			)
			(layer "F.Fab")
		)
		(fp_line
			(start 0.67945 0.3048)
			(end 0.120396 0.3048)
			(stroke
				(width 0.1)
				(type default)
			)
			(layer "F.Fab")
		)
		(fp_line
			(start 0.120396 0.3048)
			(end 0.120396 0.2794)
			(stroke
				(width 0.1)
				(type default)
			)
			(layer "F.Fab")
		)
		(fp_line
			(start -0.12065 0.3048)
			(end -0.67945 0.3048)
			(stroke
				(width 0.1)
				(type default)
			)
			(layer "F.Fab")
		)
		(fp_line
			(start -0.67945 0.3048)
			(end -0.67945 -0.305054)
			(stroke
				(width 0.1)
				(type default)
			)
			(layer "F.Fab")
		)
		(pad "1" smd circle
			(at -0.40005 0 90)
			(size 0 0)
			(layers "F.Cu" "F.Mask" "F.Paste")
			(net "PVDDCR_CPU1_P0_VCCS")
		)
		(pad "2" smd circle
			(at 0.40005 0 90)
			(size 0 0)
			(layers "F.Cu" "F.Mask" "F.Paste")
			(net "GND")
		)
	)
	(footprint ""
		(layer "F.Cu")
		(at 42.690034 -361.212892 90)
		(property "Reference" "PC454"
			(at 5.155438 -0.780034 0)
			(unlocked yes)
			(layer "F.SilkS")
			(effects
				(font
					(size 0.7874 0.5842)
					(thickness 0.1524)
				)
				(justify left)
			)
		)
		(property "Value" ""
			(at 0 0 90)
			(layer "F.Fab")
			(effects
				(font
					(size 1.27 1.27)
				)
			)
		)
		(duplicate_pad_numbers_are_jumpers no)
		(fp_line
			(start 3.400044 -3.400044)
			(end -2.146046 -3.400044)
			(stroke
				(width 0.1524)
				(type default)
			)
			(layer "F.SilkS")
		)
		(fp_line
			(start -2.146046 -3.400044)
			(end -3.400044 -2.146046)
			(stroke
				(width 0.1524)
				(type default)
			)
			(layer "F.SilkS")
		)
		(fp_line
			(start -3.400044 -2.146046)
			(end -3.400044 -0.9398)
			(stroke
				(width 0.1524)
				(type default)
			)
			(layer "F.SilkS")
		)
		(fp_line
			(start 3.400044 -0.9398)
			(end 3.400044 -3.400044)
			(stroke
				(width 0.1524)
				(type default)
			)
			(layer "F.SilkS")
		)
		(fp_line
			(start 3.400044 0.9398)
			(end 3.400044 3.400044)
			(stroke
				(width 0.1524)
				(type default)
			)
			(layer "F.SilkS")
		)
		(fp_line
			(start -3.400044 2.146046)
			(end -3.400044 0.9398)
			(stroke
				(width 0.1524)
				(type default)
			)
			(layer "F.SilkS")
		)
		(fp_line
			(start 3.400044 3.400044)
			(end -2.146046 3.400044)
			(stroke
				(width 0.1524)
				(type default)
			)
			(layer "F.SilkS")
		)
		(fp_line
			(start -2.146046 3.400044)
			(end -3.400044 2.146046)
			(stroke
				(width 0.1524)
				(type default)
			)
			(layer "F.SilkS")
		)
		(fp_line
			(start 3.400044 -3.400044)
			(end -3.400044 -3.400044)
			(stroke
				(width 0.1)
				(type default)
			)
			(layer "F.Fab")
		)
		(fp_line
			(start -3.400044 -3.400044)
			(end -3.400044 3.400044)
			(stroke
				(width 0.1)
				(type default)
			)
			(layer "F.Fab")
		)
		(fp_line
			(start 3.400044 3.400044)
			(end 3.400044 -3.400044)
			(stroke
				(width 0.1)
				(type default)
			)
			(layer "F.Fab")
		)
		(fp_line
			(start -3.400044 3.400044)
			(end 3.400044 3.400044)
			(stroke
				(width 0.1)
				(type default)
			)
			(layer "F.Fab")
		)
		(pad "1" smd rect
			(at -2.70002 0)
			(size 1.6002 3.5052)
			(layers "F.Cu" "F.Mask" "F.Paste")
			(net "SW_P12V_AUX_PVDDIO_P1_FLT")
		)
		(pad "2" smd rect
			(at 2.70002 0)
			(size 1.6002 3.5052)
			(layers "F.Cu" "F.Mask" "F.Paste")
			(net "GND")
		)
	)
	(footprint ""
		(layer "F.Cu")
		(at 24.961088 -373.44985 -90)
		(property "Reference" "PC6631"
			(at 4.54152 2.228088 0)
			(unlocked yes)
			(layer "F.SilkS")
			(effects
				(font
					(size 0.7874 0.5842)
					(thickness 0.1524)
				)
				(justify left)
			)
		)
		(property "Value" ""
			(at 0 0 270)
			(layer "F.Fab")
			(effects
				(font
					(size 1.27 1.27)
				)
			)
		)
		(duplicate_pad_numbers_are_jumpers no)
		(fp_line
			(start -1.988058 2.750058)
			(end 2.750058 2.750058)
			(stroke
				(width 0.1524)
				(type default)
			)
			(layer "F.SilkS")
		)
		(fp_line
			(start 2.750058 2.750058)
			(end 2.750058 0.9398)
			(stroke
				(width 0.1524)
				(type default)
			)
			(layer "F.SilkS")
		)
		(fp_line
			(start -2.750058 1.988058)
			(end -1.988058 2.750058)
			(stroke
				(width 0.1524)
				(type default)
			)
			(layer "F.SilkS")
		)
		(fp_line
			(start -2.750058 0.9398)
			(end -2.750058 1.988058)
			(stroke
				(width 0.1524)
				(type default)
			)
			(layer "F.SilkS")
		)
		(fp_line
			(start 2.750058 -0.9398)
			(end 2.750058 -2.750058)
			(stroke
				(width 0.1524)
				(type default)
			)
			(layer "F.SilkS")
		)
		(fp_line
			(start -2.750058 -1.988058)
			(end -2.750058 -0.9398)
			(stroke
				(width 0.1524)
				(type default)
			)
			(layer "F.SilkS")
		)
		(fp_line
			(start -1.988058 -2.750058)
			(end -2.750058 -1.988058)
			(stroke
				(width 0.1524)
				(type default)
			)
			(layer "F.SilkS")
		)
		(fp_line
			(start 2.750058 -2.750058)
			(end -1.988058 -2.750058)
			(stroke
				(width 0.1524)
				(type default)
			)
			(layer "F.SilkS")
		)
		(fp_line
			(start -2.750058 2.750058)
			(end 2.750058 2.750058)
			(stroke
				(width 0.1)
				(type default)
			)
			(layer "F.Fab")
		)
		(fp_line
			(start 2.750058 2.750058)
			(end 2.750058 -2.750058)
			(stroke
				(width 0.1)
				(type default)
			)
			(layer "F.Fab")
		)
		(fp_line
			(start -2.750058 -2.750058)
			(end -2.750058 2.750058)
			(stroke
				(width 0.1)
				(type default)
			)
			(layer "F.Fab")
		)
		(fp_line
			(start 2.750058 -2.750058)
			(end -2.750058 -2.750058)
			(stroke
				(width 0.1)
				(type default)
			)
			(layer "F.Fab")
		)
		(pad "1" smd rect
			(at -2.199894 0)
			(size 1.6002 3.0226)
			(layers "F.Cu" "F.Mask" "F.Paste")
			(net "P0V9_CPU1_RT_2D")
		)
		(pad "2" smd rect
			(at 2.199894 0)
			(size 1.6002 3.0226)
			(layers "F.Cu" "F.Mask" "F.Paste")
			(net "GND")
		)
	)
	(footprint ""
		(layer "F.Cu")
		(at 225.420428 -268.232382)
		(property "Reference" "PC6519"
			(at 0 0 0)
			(layer "F.SilkS")
			(hide yes)
			(effects
				(font
					(size 1.27 1.27)
				)
			)
		)
		(property "Value" ""
			(at 0 0 0)
			(layer "F.Fab")
			(effects
				(font
					(size 1.27 1.27)
				)
			)
		)
		(duplicate_pad_numbers_are_jumpers no)
		(fp_line
			(start -0.7874 -0.4064)
			(end 0.7874 -0.4064)
			(stroke
				(width 0.1524)
				(type default)
			)
			(layer "F.SilkS")
		)
		(fp_line
			(start -0.7874 0.4064)
			(end -0.7874 -0.4064)
			(stroke
				(width 0.1524)
				(type default)
			)
			(layer "F.SilkS")
		)
		(fp_line
			(start 0.7874 -0.4064)
			(end 0.7874 0.4064)
			(stroke
				(width 0.1524)
				(type default)
			)
			(layer "F.SilkS")
		)
		(fp_line
			(start 0.7874 0.4064)
			(end -0.7874 0.4064)
			(stroke
				(width 0.1524)
				(type default)
			)
			(layer "F.SilkS")
		)
		(fp_line
			(start -0.67945 -0.305054)
			(end -0.12065 -0.305054)
			(stroke
				(width 0.1)
				(type default)
			)
			(layer "F.Fab")
		)
		(fp_line
			(start -0.67945 0.3048)
			(end -0.67945 -0.305054)
			(stroke
				(width 0.1)
				(type default)
			)
			(layer "F.Fab")
		)
		(fp_line
			(start -0.12065 -0.305054)
			(end -0.12065 -0.2794)
			(stroke
				(width 0.1)
				(type default)
			)
			(layer "F.Fab")
		)
		(fp_line
			(start -0.12065 -0.2794)
			(end 0.12065 -0.2794)
			(stroke
				(width 0.1)
				(type default)
			)
			(layer "F.Fab")
		)
		(fp_line
			(start -0.12065 0.2794)
			(end -0.12065 0.3048)
			(stroke
				(width 0.1)
				(type default)
			)
			(layer "F.Fab")
		)
		(fp_line
			(start -0.12065 0.3048)
			(end -0.67945 0.3048)
			(stroke
				(width 0.1)
				(type default)
			)
			(layer "F.Fab")
		)
		(fp_line
			(start 0.120396 0.2794)
			(end -0.12065 0.2794)
			(stroke
				(width 0.1)
				(type default)
			)
			(layer "F.Fab")
		)
		(fp_line
			(start 0.120396 0.3048)
			(end 0.120396 0.2794)
			(stroke
				(width 0.1)
				(type default)
			)
			(layer "F.Fab")
		)
		(fp_line
			(start 0.12065 -0.3048)
			(end 0.67945 -0.3048)
			(stroke
				(width 0.1)
				(type default)
			)
			(layer "F.Fab")
		)
		(fp_line
			(start 0.12065 -0.2794)
			(end 0.12065 -0.3048)
			(stroke
				(width 0.1)
				(type default)
			)
			(layer "F.Fab")
		)
		(fp_line
			(start 0.67945 -0.3048)
			(end 0.67945 0.3048)
			(stroke
				(width 0.1)
				(type default)
			)
			(layer "F.Fab")
		)
		(fp_line
			(start 0.67945 0.3048)
			(end 0.120396 0.3048)
			(stroke
				(width 0.1)
				(type default)
			)
			(layer "F.Fab")
		)
		(pad "1" smd circle
			(at -0.40005 0)
			(size 0 0)
			(layers "F.Cu" "F.Mask" "F.Paste")
			(net "P12V_AUX")
		)
		(pad "2" smd circle
			(at 0.40005 0)
			(size 0 0)
			(layers "F.Cu" "F.Mask" "F.Paste")
			(net "GND")
		)
	)
	(footprint ""
		(layer "F.Cu")
		(at 141.624812 -49.159414)
		(property "Reference" "C6028"
			(at 0 0 0)
			(layer "F.SilkS")
			(hide yes)
			(effects
				(font
					(size 1.27 1.27)
				)
			)
		)
		(property "Value" ""
			(at 0 0 0)
			(layer "F.Fab")
			(effects
				(font
					(size 1.27 1.27)
				)
			)
		)
		(duplicate_pad_numbers_are_jumpers no)
		(fp_line
			(start -0.7874 -0.4064)
			(end 0.7874 -0.4064)
			(stroke
				(width 0.1524)
				(type default)
			)
			(layer "F.SilkS")
		)
		(fp_line
			(start -0.7874 0.4064)
			(end -0.7874 -0.4064)
			(stroke
				(width 0.1524)
				(type default)
			)
			(layer "F.SilkS")
		)
		(fp_line
			(start 0.7874 -0.4064)
			(end 0.7874 0.4064)
			(stroke
				(width 0.1524)
				(type default)
			)
			(layer "F.SilkS")
		)
		(fp_line
			(start 0.7874 0.4064)
			(end -0.7874 0.4064)
			(stroke
				(width 0.1524)
				(type default)
			)
			(layer "F.SilkS")
		)
		(fp_line
			(start -0.67945 -0.305054)
			(end -0.12065 -0.305054)
			(stroke
				(width 0.1)
				(type default)
			)
			(layer "F.Fab")
		)
		(fp_line
			(start -0.67945 0.3048)
			(end -0.67945 -0.305054)
			(stroke
				(width 0.1)
				(type default)
			)
			(layer "F.Fab")
		)
		(fp_line
			(start -0.12065 -0.305054)
			(end -0.12065 -0.2794)
			(stroke
				(width 0.1)
				(type default)
			)
			(layer "F.Fab")
		)
		(fp_line
			(start -0.12065 -0.2794)
			(end 0.12065 -0.2794)
			(stroke
				(width 0.1)
				(type default)
			)
			(layer "F.Fab")
		)
		(fp_line
			(start -0.12065 0.2794)
			(end -0.12065 0.3048)
			(stroke
				(width 0.1)
				(type default)
			)
			(layer "F.Fab")
		)
		(fp_line
			(start -0.12065 0.3048)
			(end -0.67945 0.3048)
			(stroke
				(width 0.1)
				(type default)
			)
			(layer "F.Fab")
		)
		(fp_line
			(start 0.120396 0.2794)
			(end -0.12065 0.2794)
			(stroke
				(width 0.1)
				(type default)
			)
			(layer "F.Fab")
		)
		(fp_line
			(start 0.120396 0.3048)
			(end 0.120396 0.2794)
			(stroke
				(width 0.1)
				(type default)
			)
			(layer "F.Fab")
		)
		(fp_line
			(start 0.12065 -0.3048)
			(end 0.67945 -0.3048)
			(stroke
				(width 0.1)
				(type default)
			)
			(layer "F.Fab")
		)
		(fp_line
			(start 0.12065 -0.2794)
			(end 0.12065 -0.3048)
			(stroke
				(width 0.1)
				(type default)
			)
			(layer "F.Fab")
		)
		(fp_line
			(start 0.67945 -0.3048)
			(end 0.67945 0.3048)
			(stroke
				(width 0.1)
				(type default)
			)
			(layer "F.Fab")
		)
		(fp_line
			(start 0.67945 0.3048)
			(end 0.120396 0.3048)
			(stroke
				(width 0.1)
				(type default)
			)
			(layer "F.Fab")
		)
		(pad "1" smd circle
			(at -0.40005 0)
			(size 0 0)
			(layers "F.Cu" "F.Mask" "F.Paste")
			(net "P5V_AUX")
		)
		(pad "2" smd circle
			(at 0.40005 0)
			(size 0 0)
			(layers "F.Cu" "F.Mask" "F.Paste")
			(net "GND")
		)
	)
)
